# T6G (Grand Teton) — schematic netlist excerpt (pin names and nets, part order shuffled) for the footprints in the layout excerpt that follows; sources: Cadence DE-HDL packaged netlist, KiCad conversion of 04192023_DAF0TMB3IC0_F0TG_MB_C_brd_V02_OCP.brd

U15  M24M02DRMN6TP  M24M02-DRMN6TP IC  pkg SOIC8XH  page 289
  DU1  = NC
  DU2  = NC
  E2  = U15_E2
  VSS  = GND
  SDA  = SMB_RT_CPU0_P1_ROM_SDA
  SCL  = SMB_RT_CPU0_P1_ROM_SCL
  WC_N  = GND
  VCC  = P1V8_CPU0_RT_1D

C701  Q_CAP_DIFFBUS  DIFF BUS_0.22UF 6.3V 20% X6S  pkg C0201  page 67 : \1\ = P5E_CPU1_G1_TX_C_DP<4> ; \2\ = P5E_CPU1_G1_TX_DP<4>
PL26  Q_INDUCTOR  BLM18SN220TN1D/8000MA IND  pkg SMLF  page 226 : \1\ = P12V_AUX ; \2\ = SW_P12V_AUX_PVDD18_S5_P1_FLT

(kicad_pcb
	(version 20260206)
	(generator "pcbnew")
	(generator_version "10.0")
	(general
		(thickness 1.6)
		(legacy_teardrops no)
	)
	(paper "A4")
	(title_block
		(title "04192023_DAF0TMB3IC0_F0TG_MB_C_brd_V02_OCP.brd")
		(comment 1 "Grand Teton / footprints 3493-3495 of 8354")
	)
	(layers
		(0 "F.Cu" signal "TOP")
		(4 "In1.Cu" signal "GND")
		(6 "In2.Cu" signal "IN1")
		(8 "In3.Cu" signal "GND1")
		(10 "In4.Cu" signal "IN2")
		(12 "In5.Cu" signal "GND2")
		(14 "In6.Cu" signal "IN3")
		(16 "In7.Cu" signal "GND3")
		(18 "In8.Cu" signal "VCC")
		(20 "In9.Cu" signal "VCC1")
		(22 "In10.Cu" signal "GND4")
		(24 "In11.Cu" signal "IN4")
		(26 "In12.Cu" signal "GND5")
		(28 "In13.Cu" signal "IN5")
		(30 "In14.Cu" signal "GND6")
		(32 "In15.Cu" signal "IN6")
		(34 "In16.Cu" signal "GND7")
		(2 "B.Cu" signal "BOTTOM")
		(9 "F.Adhes" user "F.Adhesive")
		(11 "B.Adhes" user "B.Adhesive")
		(13 "F.Paste" user "Package Geometry/Pastemask Top")
		(15 "B.Paste" user "Package Geometry/Pastemask Bottom")
		(5 "F.SilkS" user "Ref Des/Silkscreen Top")
		(7 "B.SilkS" user "Ref Des/Silkscreen Bottom")
		(1 "F.Mask" user "Board Geometry/Soldermask Top")
		(3 "B.Mask" user "Board Geometry/Soldermask Bottom")
		(17 "Dwgs.User" user "User.Drawings")
		(19 "Cmts.User" user "User.Comments")
		(21 "Eco1.User" user "User.Eco1")
		(23 "Eco2.User" user "User.Eco2")
		(25 "Edge.Cuts" user "Board Geometry/Outline")
		(27 "Margin" user)
		(31 "F.CrtYd" user "Package Geometry/Place Bound Top")
		(29 "B.CrtYd" user "Package Geometry/Place Bound Bottom")
		(35 "F.Fab" user "Ref Des/Assembly Top")
		(33 "B.Fab" user "Ref Des/Assembly Bottom")
	)
	(footprint ""
		(layer "F.Cu")
		(at 83.054444 -152.093676 180)
		(property "Reference" "PL26"
			(at 0 0 180)
			(layer "F.SilkS")
			(hide yes)
			(effects
				(font
					(size 1.27 1.27)
				)
			)
		)
		(property "Value" ""
			(at 0 0 180)
			(layer "F.Fab")
			(effects
				(font
					(size 1.27 1.27)
				)
			)
		)
		(duplicate_pad_numbers_are_jumpers no)
		(fp_line
			(start 1.27 0.5842)
			(end 1.27 -0.5842)
			(stroke
				(width 0.1524)
				(type default)
			)
			(layer "F.SilkS")
		)
		(fp_line
			(start 1.27 0.5842)
			(end -1.27 0.5842)
			(stroke
				(width 0.1524)
				(type default)
			)
			(layer "F.SilkS")
		)
		(fp_line
			(start -1.27 0.5842)
			(end -1.27 -0.5842)
			(stroke
				(width 0.1524)
				(type default)
			)
			(layer "F.SilkS")
		)
		(fp_line
			(start -1.27 -0.5588)
			(end -1.27 -0.5842)
			(stroke
				(width 0.1524)
				(type default)
			)
			(layer "F.SilkS")
		)
		(fp_line
			(start -1.27 -0.5842)
			(end 1.27 -0.5842)
			(stroke
				(width 0.1524)
				(type default)
			)
			(layer "F.SilkS")
		)
		(fp_line
			(start 1.1938 0.4064)
			(end 0.9144 0.4064)
			(stroke
				(width 0.1)
				(type default)
			)
			(layer "F.Fab")
		)
		(fp_line
			(start 1.1938 -0.406654)
			(end 1.1938 0.4064)
			(stroke
				(width 0.1)
				(type default)
			)
			(layer "F.Fab")
		)
		(fp_line
			(start 0.9144 0.508)
			(end -0.9144 0.508)
			(stroke
				(width 0.1)
				(type default)
			)
			(layer "F.Fab")
		)
		(fp_line
			(start 0.9144 0.4064)
			(end 0.9144 0.508)
			(stroke
				(width 0.1)
				(type default)
			)
			(layer "F.Fab")
		)
		(fp_line
			(start 0.9144 -0.406654)
			(end 1.1938 -0.406654)
			(stroke
				(width 0.1)
				(type default)
			)
			(layer "F.Fab")
		)
		(fp_line
			(start 0.9144 -0.508)
			(end 0.9144 -0.406654)
			(stroke
				(width 0.1)
				(type default)
			)
			(layer "F.Fab")
		)
		(fp_line
			(start -0.9144 0.508)
			(end -0.9144 0.406654)
			(stroke
				(width 0.1)
				(type default)
			)
			(layer "F.Fab")
		)
		(fp_line
			(start -0.9144 0.406654)
			(end -1.194308 0.406654)
			(stroke
				(width 0.1)
				(type default)
			)
			(layer "F.Fab")
		)
		(fp_line
			(start -0.9144 -0.406654)
			(end -0.9144 -0.508)
			(stroke
				(width 0.1)
				(type default)
			)
			(layer "F.Fab")
		)
		(fp_line
			(start -0.9144 -0.508)
			(end 0.9144 -0.508)
			(stroke
				(width 0.1)
				(type default)
			)
			(layer "F.Fab")
		)
		(fp_line
			(start -1.194308 0.406654)
			(end -1.194308 -0.406654)
			(stroke
				(width 0.1)
				(type default)
			)
			(layer "F.Fab")
		)
		(fp_line
			(start -1.194308 -0.406654)
			(end -0.9144 -0.406654)
			(stroke
				(width 0.1)
				(type default)
			)
			(layer "F.Fab")
		)
		(pad "1" smd rect
			(at -0.7366 0 90)
			(size 0.7112 0.8128)
			(layers "F.Cu" "F.Mask" "F.Paste")
			(net "P12V_AUX")
		)
		(pad "2" smd rect
			(at 0.7366 0 90)
			(size 0.7112 0.8128)
			(layers "F.Cu" "F.Mask" "F.Paste")
			(net "SW_P12V_AUX_PVDD18_S5_P1_FLT")
		)
	)
	(footprint ""
		(layer "F.Cu")
		(at 47.462694 -17.623536 90)
		(property "Reference" "C701"
			(at 0 0 90)
			(layer "F.SilkS")
			(hide yes)
			(effects
				(font
					(size 1.27 1.27)
				)
			)
		)
		(property "Value" ""
			(at 0 0 90)
			(layer "F.Fab")
			(effects
				(font
					(size 1.27 1.27)
				)
			)
		)
		(duplicate_pad_numbers_are_jumpers no)
		(fp_line
			(start 0.299974 -0.150114)
			(end 0.299974 0.150114)
			(stroke
				(width 0.1)
				(type default)
			)
			(layer "F.Fab")
		)
		(fp_line
			(start -0.299974 -0.150114)
			(end 0.299974 -0.150114)
			(stroke
				(width 0.1)
				(type default)
			)
			(layer "F.Fab")
		)
		(fp_line
			(start 0.299974 0.150114)
			(end -0.299974 0.150114)
			(stroke
				(width 0.1)
				(type default)
			)
			(layer "F.Fab")
		)
		(fp_line
			(start -0.299974 0.150114)
			(end -0.299974 -0.150114)
			(stroke
				(width 0.1)
				(type default)
			)
			(layer "F.Fab")
		)
		(pad "1" smd rect
			(at -0.2667 0 90)
			(size 0.3048 0.381)
			(layers "F.Cu" "F.Mask" "F.Paste")
			(net "P5E_CPU1_G1_TX_C_DP<4>")
		)
		(pad "2" smd rect
			(at 0.2667 0 90)
			(size 0.3048 0.381)
			(layers "F.Cu" "F.Mask" "F.Paste")
			(net "P5E_CPU1_G1_TX_DP<4>")
		)
	)
	(footprint ""
		(layer "F.Cu")
		(at 290.399724 -403.086062)
		(property "Reference" "U15"
			(at -0.024384 -3.107436 0)
			(unlocked yes)
			(layer "F.SilkS")
			(effects
				(font
					(size 0.7874 0.5842)
					(thickness 0.1524)
				)
				(justify left)
			)
		)
		(property "Value" ""
			(at 0 0 0)
			(layer "F.Fab")
			(effects
				(font
					(size 1.27 1.27)
				)
			)
		)
		(duplicate_pad_numbers_are_jumpers no)
		(fp_line
			(start -1.8288 -2.500122)
			(end -1.8288 2.500122)
			(stroke
				(width 0.1524)
				(type default)
			)
			(layer "F.SilkS")
		)
		(fp_line
			(start -1.8288 2.500122)
			(end 1.8288 2.500122)
			(stroke
				(width 0.1524)
				(type default)
			)
			(layer "F.SilkS")
		)
		(fp_line
			(start -1.077722 -2.500122)
			(end -1.8288 -2.500122)
			(stroke
				(width 0.1524)
				(type default)
			)
			(layer "F.SilkS")
		)
		(fp_line
			(start 0 -1.4224)
			(end -1.077722 -2.500122)
			(stroke
				(width 0.1524)
				(type default)
			)
			(layer "F.SilkS")
		)
		(fp_line
			(start 1.077722 -2.500122)
			(end 0 -1.4224)
			(stroke
				(width 0.1524)
				(type default)
			)
			(layer "F.SilkS")
		)
		(fp_line
			(start 1.8288 -2.500122)
			(end 1.077722 -2.500122)
			(stroke
				(width 0.1524)
				(type default)
			)
			(layer "F.SilkS")
		)
		(fp_line
			(start 1.8288 2.500122)
			(end 1.8288 -2.500122)
			(stroke
				(width 0.1524)
				(type default)
			)
			(layer "F.SilkS")
		)
		(fp_poly
			(pts
				(xy -1.170432 -3.243326) (xy -2.085594 -3.684778) (xy -2.069592 -2.54889)
			)
			(stroke
				(width 0)
				(type default)
			)
			(fill yes)
			(layer "F.SilkS")
		)
		(fp_line
			(start -1.999996 -2.500122)
			(end -1.999996 2.500122)
			(stroke
				(width 0.1)
				(type default)
			)
			(layer "F.Fab")
		)
		(fp_line
			(start -1.999996 2.500122)
			(end 1.999996 2.500122)
			(stroke
				(width 0.1)
				(type default)
			)
			(layer "F.Fab")
		)
		(fp_line
			(start 1.999996 -2.500122)
			(end -1.999996 -2.500122)
			(stroke
				(width 0.1)
				(type default)
			)
			(layer "F.Fab")
		)
		(fp_line
			(start 1.999996 2.500122)
			(end 1.999996 -2.500122)
			(stroke
				(width 0.1)
				(type default)
			)
			(layer "F.Fab")
		)
		(fp_poly
			(pts
				(xy -4.5085 -2.413) (xy -4.5085 -1.397) (xy -3.4925 -1.905)
			)
			(stroke
				(width 0)
				(type default)
			)
			(fill yes)
			(layer "F.Fab")
		)
		(pad "1" smd rect
			(at -2.599944 -1.905 270)
			(size 0.889 1.27)
			(layers "F.Cu" "F.Mask" "F.Paste")
			(net "Net_10843")
		)
		(pad "2" smd rect
			(at -2.599944 -0.635 270)
			(size 0.889 1.27)
			(layers "F.Cu" "F.Mask" "F.Paste")
			(net "Net_10842")
		)
		(pad "3" smd rect
			(at -2.599944 0.635 270)
			(size 0.889 1.27)
			(layers "F.Cu" "F.Mask" "F.Paste")
			(net "U15_E2")
		)
		(pad "4" smd rect
			(at -2.599944 1.905 270)
			(size 0.889 1.27)
			(layers "F.Cu" "F.Mask" "F.Paste")
			(net "GND")
		)
		(pad "5" smd rect
			(at 2.599944 1.905 270)
			(size 0.889 1.27)
			(layers "F.Cu" "F.Mask" "F.Paste")
			(net "SMB_RT_CPU0_P1_ROM_SDA")
		)
		(pad "6" smd rect
			(at 2.599944 0.635 270)
			(size 0.889 1.27)
			(layers "F.Cu" "F.Mask" "F.Paste")
			(net "SMB_RT_CPU0_P1_ROM_SCL")
		)
		(pad "7" smd rect
			(at 2.599944 -0.635 270)
			(size 0.889 1.27)
			(layers "F.Cu" "F.Mask" "F.Paste")
			(net "GND")
		)
		(pad "8" smd rect
			(at 2.599944 -1.905 270)
			(size 0.889 1.27)
			(layers "F.Cu" "F.Mask" "F.Paste")
			(net "P1V8_CPU0_RT_1D")
		)
	)
)
